FILE_TYPE = CONNECTIVITY;
{Allegro Design Entry HDL 17.4-2019 S026 (4007227) 1/17/2022}
"PAGE_NUMBER" = 335;
0"NC";
1"GND\g";
2"GND\g";
3"GND\g";
4"P5E_CPU0_G3_RX_DN<15:0>";
5"P5E_CPU0_G3_RX_DP<15:0>";
6"P5E_CPU0_G3_TX_C_DN<15:0>";
7"P5E_CPU0_G3_TX_C_DP<15:0>";
8"OCP_SFF_MAIN_PWR_EN";
9"FM_OCP_SFF_PWR_GOOD";
10"SMB_OCP_SFF_3V3AUX_BUF_SDA";
11"SMB_OCP_SFF_3V3AUX_BUF_SCL";
12"RST_SMB_OCP_SFF_N";
13"OCP_SFF_PRSNTA_R_N";
14"CLK_100M_CPU0_CLK05_DP";
15"CLK_50M_NCSI_OCP_SFF_ISO";
16"SMB_OCP_SFF_3V3AUX_BUF_R_SCL";
17"GND\g";
18"RST_PERST1_OCP_SFF_N";
19"OCP_SFF_PRSNT2_R_N";
20"CLK_100M_CPU0_CLK03_DN";
21"SMB_OCP_SFF_3V3AUX_BUF_R_SDA";
22"P12V_OCP_SFF_R\g";
23"P12V_OCP_SFF_R\g";
24"P3V3_OCP_SFF\g";
25"GND\g";
26"P3V3_OCP_SFF\g";
27"P3V3_OCP_SFF\g";
28"GND\g";
29"GND\g";
30"P3V3_OCP_SFF\g";
31"GND\g";
32"GND\g";
33"NCSI_OCP_SFF_TXD1";
34"CLK_100M_CPU0_CLK05_DN";
35"OCP_SFF_MAIN_PWR_EN_R";
36"SGPIO_OCP_SFF_LD_N";
37"SGPIO_OCP_SFF_DATAOUT";
38"SGPIO_OCP_SFF_CLK";
39"CLK_100M_CPU0_CLK04_DN";
40"CLK_100M_CPU0_CLK04_DP";
41"SGPIO_OCP_SFF_DATAIN";
42"OCP_SFF_ID0";
43"NCSI_OCP_SFF_RXD1";
44"OCP_SFF_AUX_PWR_EN";
45"OCP_SFF_AUX_PWR_EN"CDS_PHYS_NET_NAME"OCP_SFF_AUX_PWR_EN";
46"P5E_CPU0_G3_RX_DP<2>";
47"P5E_CPU0_G3_RX_DN<2>";
48"CLK_100M_CPU0_CLK03_DP";
49"P5E_CPU0_G3_RX_DP<0>";
50"P5E_CPU0_G3_RX_DN<1>";
51"CLK_100M_CPU0_CLK02_DP";
52"OCP_SFF_AUX_PWR_EN_R";
53"OCP_SFF_MAIN_PWR_EN"CDS_PHYS_NET_NAME"OCP_SFF_MAIN_PWR_EN";
54"FM_OCP_SFF_PWR_GOOD"CDS_PHYS_NET_NAME"FM_OCP_SFF_PWR_GOOD";
55"RST_PERST0_OCP_SFF_N";
56"OCP_SFF_BIF2_R_N";
57"OCP_SFF_BIF1_R_N";
58"OCP_SFF_BIF0_R_N";
59"CLK_100M_CPU0_CLK02_DN";
60"OCP_SFF_PRSNT0_R_N";
61"OCP_SFF_ID0";
62"OCP_SFF_ID1";
63"OCP_SFF_PRSNT3_R_N";
64"TP_OCP_SFF_B68";
65"TP_OCP_SFF_B69";
66"SGPIO_OCP_SFF_DATAIN";
67"SGPIO_OCP_SFF_CLK";
68"SGPIO_OCP_SFF_DATAOUT";
69"SGPIO_OCP_SFF_LD_N";
70"P5E_CPU0_G3_TX_C_DN<14>";
71"P5E_CPU0_G3_TX_C_DP<14>";
72"P5E_CPU0_G3_TX_C_DP<15>";
73"P5E_CPU0_G3_TX_C_DN<15>";
74"P5E_CPU0_G3_TX_C_DN<13>";
75"P5E_CPU0_G3_TX_C_DN<11>";
76"P5E_CPU0_G3_TX_C_DN<10>";
77"P5E_CPU0_G3_TX_C_DP<11>";
78"P5E_CPU0_G3_TX_C_DN<9>";
79"P5E_CPU0_G3_TX_C_DP<9>";
80"P5E_CPU0_G3_TX_C_DP<8>";
81"P5E_CPU0_G3_TX_C_DP<10>";
82"P5E_CPU0_G3_TX_C_DP<12>";
83"P5E_CPU0_G3_TX_C_DP<13>";
84"OCP_SFF_ISO_BIF2_EN";
85"OCP_SFF_ISO_BIF0_EN";
86"OCP_SFF_ISO_BIF1_EN";
87"P5E_CPU0_G3_TX_C_DP<5>";
88"P5E_CPU0_G3_TX_C_DP<4>";
89"P5E_CPU0_G3_TX_C_DP<7>";
90"P5E_CPU0_G3_TX_C_DP<6>";
91"P5E_CPU0_G3_TX_C_DN<5>";
92"P5E_CPU0_G3_TX_C_DN<3>";
93"P5E_CPU0_G3_TX_C_DP<3>";
94"P5E_CPU0_G3_RX_DP<10>";
95"P5E_CPU0_G3_RX_DP<12>";
96"P5E_CPU0_G3_RX_DN<12>";
97"P5E_CPU0_G3_RX_DP<11>";
98"P5E_CPU0_G3_RX_DN<9>";
99"P5E_CPU0_G3_RX_DP<8>";
100"P5E_CPU0_G3_RX_DN<8>";
101"P5E_CPU0_G3_RX_DN<3>";
102"P5E_CPU0_G3_RX_DN<5>";
103"P5E_CPU0_G3_RX_DP<7>";
104"P5E_CPU0_G3_RX_DN<7>";
105"P5E_CPU0_G3_RX_DP<5>";
106"P5E_CPU0_G3_RX_DP<4>";
107"P5E_CPU0_G3_RX_DN<4>";
108"P5E_CPU0_G3_RX_DN<0>";
109"P5E_CPU0_G3_RX_DP<1>";
110"NCSI_OCP_SFF_TXD0";
111"P5E_CPU0_G3_RX_DP<14>";
112"P5E_CPU0_G3_TX_C_DN<12>";
113"NCSI_OCP_SFF_TX_EN";
114"P5E_CPU0_G3_RX_DP<6>";
115"P5E_CPU0_G3_RX_DN<6>";
116"P5E_CPU0_G3_RX_DP<13>";
117"P5E_CPU0_G3_RX_DN<14>";
118"OCP_SFF_PRSNT1_R_N";
119"P5E_CPU0_G3_RX_DP<3>";
120"NCSI_OCP_SFF_CRS_DV";
121"NCSI_OCP_SFF_RXD0";
122"P5E_CPU0_G3_TX_C_DN<8>";
123"P5E_CPU0_G3_TX_C_DN<7>";
124"P5E_CPU0_G3_TX_C_DN<6>";
125"P5E_CPU0_G3_TX_C_DN<4>";
126"P5E_CPU0_G3_TX_C_DP<1>";
127"P5E_CPU0_G3_TX_C_DN<1>";
128"P5E_CPU0_G3_TX_C_DP<2>";
129"P5E_CPU0_G3_TX_C_DN<2>";
130"P5E_CPU0_G3_TX_C_DP<0>";
131"P5E_CPU0_G3_TX_C_DN<0>";
132"P5E_CPU0_G3_RX_DP<15>";
133"USB2_P11_DP";
134"P5E_CPU0_G3_RX_DP<9>";
135"USB2_CPU0_P11_DN";
136"USB2_CPU0_P11_DP";
137"P5E_CPU0_G3_RX_DN<15>";
138"OCP_SFF_PWRBRK_N";
139"P5E_CPU0_G3_RX_DN<11>";
140"P5E_CPU0_G3_RX_DN<10>";
141"USB2_P11_DN";
142"P5E_CPU0_G3_RX_DN<13>";
143"RST_PERST3_OCP_SFF_N";
144"IRQ_LVC3_OCP_SFF_WAKE_N";
145"OCP_SFF_ISO1_RBT_ARB_IN";
146"OCP_SFF_ID1";
147"OCP_SFF_ISO2_RBT_ARB_OUT";
148"RST_PERST2_OCP_SFF_N";
%"UNIVERSAL_GND"
"1","(-4300,1500)","0","pure_quanta_power","I1";
;
ROOM"IO_SLOT"
CDS_LIB"pure_quanta_power"
HDL_POWER"GND";
"A"1;
%"TAP"
"1","(925,3350)","0","standard","I100";
;
CDS_LIB"standard"
BODY_TYPE"PLUMBING"
HDL_TAP"TRUE";
"B \NAC \NWC"4;
"S \NAC"
BN"12"96;
%"TAP"
"1","(925,3500)","0","standard","I101";
;
CDS_LIB"standard"
BODY_TYPE"PLUMBING"
HDL_TAP"TRUE";
"B \NAC \NWC"4;
"S \NAC"
BN"11"139;
%"TAP"
"1","(775,3600)","0","standard","I102";
;
CDS_LIB"standard"
BODY_TYPE"PLUMBING"
HDL_TAP"TRUE";
"B \NAC \NWC"5;
"S \NAC"
BN"10"94;
%"TAP"
"1","(775,3750)","0","standard","I103";
;
CDS_LIB"standard"
BODY_TYPE"PLUMBING"
HDL_TAP"TRUE";
"B \NAC \NWC"5;
"S \NAC"
BN"9"134;
%"TAP"
"1","(775,3900)","0","standard","I104";
;
CDS_LIB"standard"
BODY_TYPE"PLUMBING"
HDL_TAP"TRUE";
"B \NAC \NWC"5;
"S \NAC"
BN"8"99;
%"TAP"
"1","(925,3650)","0","standard","I105";
;
CDS_LIB"standard"
BODY_TYPE"PLUMBING"
HDL_TAP"TRUE";
"B \NAC \NWC"4;
"S \NAC"
BN"10"140;
%"TAP"
"1","(925,3800)","0","standard","I106";
;
CDS_LIB"standard"
BODY_TYPE"PLUMBING"
HDL_TAP"TRUE";
"B \NAC \NWC"4;
"S \NAC"
BN"9"98;
%"TAP"
"1","(925,3950)","0","standard","I107";
;
CDS_LIB"standard"
BODY_TYPE"PLUMBING"
HDL_TAP"TRUE";
"B \NAC \NWC"4;
"S \NAC"
BN"8"100;
%"Q_RES"
"1","(1525,2700)","0","pure_quanta","I108";
;
LOCATION"R46"
$SEC"1"
CDS_SEC"1"
PACK_TYPE"0402LF"
TOLERANCE"5%"
VALUE"0"
CDS_LIB"pure_quanta"
WATTAGE"1/16W"
MATERIAL"CHIP"
PART_NUMBER"CS00002JB13";
"B"
$PN"2"136;
"A"
$PN"1"133;
%"UNIVERSAL_GND"
"1","(2325,1400)","0","pure_quanta_power","I109";
;
ROOM"IO_SLOT"
CDS_LIB"pure_quanta_power"
HDL_POWER"GND";
"A"32;
%"UNIVERSAL_GND"
"1","(-3825,1500)","0","pure_quanta_power","I11";
;
ROOM"IO_SLOT"
CDS_LIB"pure_quanta_power"
HDL_POWER"GND";
"A"2;
%"Q_CAP"
"1","(2850,1900)","0","pure_quanta","I110";
;
LOCATION"C1237"
$SEC"1"
CDS_SEC"1"
MATERIAL"X7R"
PACK_TYPE"0402"
TOLERANCE"10%"
VOLTAGE"25V"
VALUE"0.1UF"
CDS_LIB"pure_quanta"
PART_NUMBER"CH4104K1B00";
"B"
$PN"2"31;
"A"
$PN"1"30;
%"Q_CAP"
"1","(3100,1900)","0","pure_quanta","I111";
;
LOCATION"C1238"
$SEC"1"
CDS_SEC"1"
PACK_TYPE"0402"
VALUE"0.1UF"
VOLTAGE"25V"
TOLERANCE"10%"
MATERIAL"X7R"
CDS_LIB"pure_quanta"
PART_NUMBER"CH4104K1B00";
"B"
$PN"2"31;
"A"
$PN"1"30;
%"Q_CAP"
"1","(3375,1900)","0","pure_quanta","I112";
;
LOCATION"C1239"
$SEC"1"
CDS_SEC"1"
VALUE"0.1UF"
VOLTAGE"25V"
TOLERANCE"10%"
PACK_TYPE"0402"
MATERIAL"X7R"
CDS_LIB"pure_quanta"
PART_NUMBER"CH4104K1B00";
"B"
$PN"2"31;
"A"
$PN"1"30;
%"UNIVERSAL_GND"
"1","(3650,1550)","0","pure_quanta_power","I113";
;
ROOM"IO_SLOT"
CDS_LIB"pure_quanta_power"
HDL_POWER"GND";
"A"31;
%"Q_CAP"
"1","(3650,1900)","0","pure_quanta","I114";
;
LOCATION"C1240"
$SEC"1"
CDS_SEC"1"
VOLTAGE"25V"
TOLERANCE"10%"
MATERIAL"X7R"
VALUE"0.1UF"
PACK_TYPE"0402"
CDS_LIB"pure_quanta"
PART_NUMBER"CH4104K1B00";
"B"
$PN"2"31;
"A"
$PN"1"30;
%"UNIVERSAL_POWER"
"1","(2850,2250)","0","pure_quanta_power","I117";
;
HDL_POWER"P3V3_OCP_SFF"
CDS_LIB"pure_quanta_power";
"A"30;
%"TAP"
"1","(775,4250)","0","standard","I118";
;
CDS_LIB"standard"
BODY_TYPE"PLUMBING"
HDL_TAP"TRUE";
"B \NAC \NWC"5;
"S \NAC"
BN"7"103;
%"TAP"
"1","(775,4400)","0","standard","I119";
;
CDS_LIB"standard"
BODY_TYPE"PLUMBING"
HDL_TAP"TRUE";
"B \NAC \NWC"5;
"S \NAC"
BN"6"114;
%"Q_RES"
"2","(-3825,1725)","0","pure_quanta","I12";
;
LOCATION"R34"
$SEC"1"
CDS_SEC"1"
WATTAGE"1/16W"
TOLERANCE"1%"
PACK_TYPE"0402LF"
MATERIAL"CHIP"
VALUE"4.7K"
CDS_LIB"pure_quanta"
PART_NUMBER"CS24702FB06";
"A"
$PN"1"62;
"B"
$PN"2"2;
%"TAP"
"1","(775,4550)","0","standard","I120";
;
CDS_LIB"standard"
BODY_TYPE"PLUMBING"
HDL_TAP"TRUE";
"B \NAC \NWC"5;
"S \NAC"
BN"5"105;
%"TAP"
"1","(925,4300)","0","standard","I121";
;
CDS_LIB"standard"
BODY_TYPE"PLUMBING"
HDL_TAP"TRUE";
"B \NAC \NWC"4;
"S \NAC"
BN"7"104;
%"TAP"
"1","(925,4600)","0","standard","I122";
;
CDS_LIB"standard"
BODY_TYPE"PLUMBING"
HDL_TAP"TRUE";
"B \NAC \NWC"4;
"S \NAC"
BN"5"102;
%"TAP"
"1","(925,4450)","0","standard","I123";
;
CDS_LIB"standard"
BODY_TYPE"PLUMBING"
HDL_TAP"TRUE";
"B \NAC \NWC"4;
"S \NAC"
BN"6"115;
%"TAP"
"1","(775,4700)","0","standard","I124";
;
CDS_LIB"standard"
BODY_TYPE"PLUMBING"
HDL_TAP"TRUE";
"B \NAC \NWC"5;
"S \NAC"
BN"4"106;
%"TAP"
"1","(775,5000)","0","standard","I125";
;
CDS_LIB"standard"
BODY_TYPE"PLUMBING"
HDL_TAP"TRUE";
"B \NAC \NWC"5;
"S \NAC"
BN"3"119;
%"TAP"
"1","(925,4750)","0","standard","I126";
;
CDS_LIB"standard"
BODY_TYPE"PLUMBING"
HDL_TAP"TRUE";
"B \NAC \NWC"4;
"S \NAC"
BN"4"107;
%"TAP"
"1","(925,5050)","0","standard","I127";
;
CDS_LIB"standard"
BODY_TYPE"PLUMBING"
HDL_TAP"TRUE";
"B \NAC \NWC"4;
"S \NAC"
BN"3"101;
%"TAP"
"1","(775,5150)","0","standard","I128";
;
CDS_LIB"standard"
BODY_TYPE"PLUMBING"
HDL_TAP"TRUE";
"B \NAC \NWC"5;
"S \NAC"
BN"2"46;
%"TAP"
"1","(775,5300)","0","standard","I129";
;
CDS_LIB"standard"
BODY_TYPE"PLUMBING"
HDL_TAP"TRUE";
"B \NAC \NWC"5;
"S \NAC"
BN"1"109;
%"TAP"
"1","(775,5450)","0","standard","I130";
;
CDS_LIB"standard"
BODY_TYPE"PLUMBING"
HDL_TAP"TRUE";
"B \NAC \NWC"5;
"S \NAC"
BN"0"49;
%"TAP"
"1","(925,5200)","0","standard","I131";
;
CDS_LIB"standard"
BODY_TYPE"PLUMBING"
HDL_TAP"TRUE";
"B \NAC \NWC"4;
"S \NAC"
BN"2"47;
%"TAP"
"1","(925,5350)","0","standard","I132";
;
CDS_LIB"standard"
BODY_TYPE"PLUMBING"
HDL_TAP"TRUE";
"B \NAC \NWC"4;
"S \NAC"
BN"1"50;
%"TAP"
"1","(925,5500)","0","standard","I133";
;
CDS_LIB"standard"
BODY_TYPE"PLUMBING"
HDL_TAP"TRUE";
"B \NAC \NWC"4;
"S \NAC"
BN"0"108;
%"UNIVERSAL_GND"
"1","(3125,5325)","0","pure_quanta_power","I155";
;
ROOM"IO_SLOT"
CDS_LIB"pure_quanta_power"
HDL_POWER"GND";
"A"3;
%"TAP"
"1","(775,2850)","0","standard","I162";
;
CDS_LIB"standard"
BODY_TYPE"PLUMBING"
HDL_TAP"TRUE";
"B \NAC \NWC"5;
"S \NAC"
BN"15"132;
%"Q_CAP"
"1","(1775,1750)","0","pure_quanta","I163";
;
LOCATION"C27"
$SEC"1"
CDS_SEC"1"
TOLERANCE"10%"
VALUE"0.1UF"
VOLTAGE"25V"
PACK_TYPE"0402"
MATERIAL"X7R"
CDS_LIB"pure_quanta"
PART_NUMBER"CH4104K1B00";
"B"
$PN"2"32;
"A"
$PN"1"22;
%"Q_CAP"
"1","(2325,1750)","0","pure_quanta","I164";
;
LOCATION"C1236"
$SEC"1"
CDS_SEC"1"
PACK_TYPE"0402"
VOLTAGE"25V"
TOLERANCE"10%"
VALUE"0.1UF"
MATERIAL"X7R"
CDS_LIB"pure_quanta"
PART_NUMBER"CH4104K1B00";
"B"
$PN"2"32;
"A"
$PN"1"22;
%"Q_RES"
"1","(1525,2750)","0","pure_quanta","I166";
;
LOCATION"R42"
$SEC"1"
CDS_SEC"1"
PACK_TYPE"0402LF"
MATERIAL"CHIP"
WATTAGE"1/16W"
VALUE"0"
TOLERANCE"5%"
CDS_LIB"pure_quanta"
PART_NUMBER"CS00002JB13";
"B"
$PN"2"135;
"A"
$PN"1"141;
%"TAP"
"1","(-1575,3350)","2","standard","I167";
;
CDS_LIB"standard"
BODY_TYPE"PLUMBING"
HDL_TAP"TRUE";
"B \NAC \NWC"7;
"S \NAC"
BN"12"82;
%"SCONN168_ME1016810202011"
"1","(-350,4725)","0","pure_quanta","I168";
;
LOCATION"J38"
SEC"1"
PART_TYPE"SMLF"
MATERIAL"IO"
VALUE"SCONN168_ME1016810202011"
SEC_TYPE""
CDS_LIB"pure_quanta"
CDS_LMAN_SYM_OUTLINE"-500,2475,500,-2475"
NEEDS_NO_SIZE"TRUE"
PART_NUMBER"DFHSG8FR011";
"G5"
$PN"G5"17;
"G4"
$PN"G4"17;
"G3"
$PN"G3"17;
"G2"
$PN"G2"17;
"G1"
$PN"G1"17;
"PRSNTB3# \B"
$PN"B70"63;
"RFU1_NC_B69"
$PN"B69"65;
"RFU1_NC_B68"
$PN"B68"64;
"GND_B67"
$PN"B67"28;
"PETP15"
$PN"B66"73;
"PETN15"
$PN"B65"72;
"GND_B64"
$PN"B64"28;
"PETP14"
$PN"B63"70;
"PETN14"
$PN"B62"71;
"GND_B61"
$PN"B61"28;
"PETP13"
$PN"B60"74;
"PETN13"
$PN"B59"83;
"GND_B58"
$PN"B58"28;
"PETP12"
$PN"B57"112;
"PWRBRK0# \B"
$PN"A70"138;
"USB_DATP"
$PN"A69"133;
"USB_DATN"
$PN"A68"141;
"GND_A67"
$PN"A67"17;
"PERP15"
$PN"A66"132;
"PERN15"
$PN"A65"137;
"GND_A64"
$PN"A64"17;
"PERP14"
$PN"A63"111;
"PERN14"
$PN"A62"117;
"GND_A61"
$PN"A61"17;
"PERP13"
$PN"A60"116;
"PERN13"
$PN"A59"142;
"GND_A58"
$PN"A58"17;
"PERP12"
$PN"A57"95;
"PERN12"
$PN"A56"96;
"GND_A55"
$PN"A55"17;
"PERP11"
$PN"A54"97;
"PERN11"
$PN"A53"139;
"GND_A52"
$PN"A52"17;
"PERP10"
$PN"A51"94;
"PERN10"
$PN"A50"140;
"GND_A49"
$PN"A49"17;
"PERP9"
$PN"A48"134;
"PERN9"
$PN"A47"98;
"GND_A46"
$PN"A46"17;
"PERP8"
$PN"A45"99;
"PERN8"
$PN"A44"100;
"GND_A43"
$PN"A43"17;
"PRSNTB1# \B"
$PN"A42"118;
"GND_A41"
$PN"A41"17;
"PERP7"
$PN"A40"103;
"PERN7"
$PN"A39"104;
"GND_A38"
$PN"A38"17;
"PERP6"
$PN"A37"114;
"PERN6"
$PN"A36"115;
"GND_A35"
$PN"A35"17;
"PERP5"
$PN"A34"105;
"PERN5"
$PN"A33"102;
"GND_A32"
$PN"A32"17;
"PERP4"
$PN"A31"106;
"PERN4"
$PN"A30"107;
"GND_A29"
$PN"A29"17;
"GND_A28"
$PN"A28"17;
"PERP3"
$PN"A27"119;
"PERN3"
$PN"A26"101;
"GND_A25"
$PN"A25"17;
"PERP2"
$PN"A24"46;
"PERN2"
$PN"A23"47;
"GND_A22"
$PN"A22"17;
"PERP1"
$PN"A21"109;
"PERN1"
$PN"A20"50;
"GND_A19"
$PN"A19"17;
"PERP0"
$PN"A18"49;
"PERN0"
$PN"A17"108;
"GND_A16"
$PN"A16"17;
"REFCLKP1"
$PN"A15"48;
"REFCLKN1"
$PN"A14"20;
"GND_A13"
$PN"A13"17;
"PRSNTB2# \B"
$PN"A12"19;
"PERST1# \B"
$PN"A11"18;
"PRSNTA# \B"
$PN"A10"13;
"SMRST# \B"
$PN"A9"12;
"SMDAT"
$PN"A8"21;
"SMCLK"
$PN"A7"16;
"GND_A6"
$PN"A6"17;
"GND_A5"
$PN"A5"17;
"GND_A4"
$PN"A4"17;
"GND_A3"
$PN"A3"17;
"GND_A2"
$PN"A2"17;
"GND_A1"
$PN"A1"17;
"RBT_CLK_IN"
$PN"OA14"15;
"GND_OA13"
$PN"OA13"17;
"REFCLKP3"
$PN"OA12"14;
"REFCLKN3"
$PN"OA11"34;
"GND_OA10"
$PN"OA10"17;
"RBT_TXD0"
$PN"OA9"110;
"RBT_TXD1"
$PN"OA8"33;
"RBT_TX_EN"
$PN"OA7"113;
"SLOT_ID1"
$PN"OA6"146;
"RBT_ARB_OUT"
$PN"OA5"147;
"RBT_ARB_IN"
$PN"OA4"145;
"WAKE# \B"
$PN"OA3"144;
"PERST3# \B"
$PN"OA2"143;
"PERST2# \B"
$PN"OA1"148;
"PETN12"
$PN"B56"82;
"GND_B55"
$PN"B55"28;
"PETP11"
$PN"B54"75;
"PETN11"
$PN"B53"77;
"GND_B52"
$PN"B52"28;
"PETP10"
$PN"B51"76;
"PETN10"
$PN"B50"81;
"GND_B49"
$PN"B49"28;
"PETP9"
$PN"B48"78;
"PETN9"
$PN"B47"79;
"GND_B46"
$PN"B46"28;
"PETP8"
$PN"B45"122;
"PETN8"
$PN"B44"80;
"GND_B43"
$PN"B43"28;
"PRSNTB0# \B"
$PN"B42"60;
"GND_B41"
$PN"B41"28;
"PETP7"
$PN"B40"123;
"PETN7"
$PN"B39"89;
"GND_B38"
$PN"B38"28;
"PETP6"
$PN"B37"124;
"PETN6"
$PN"B36"90;
"GND_B35"
$PN"B35"28;
"PETP5"
$PN"B34"91;
"PETN5"
$PN"B33"87;
"GND_B32"
$PN"B32"28;
"PETP4"
$PN"B31"125;
"PETN4"
$PN"B30"88;
"GND_B29"
$PN"B29"28;
"GND_B28"
$PN"B28"28;
"PETP3"
$PN"B27"92;
"PETN3"
$PN"B26"93;
"GND_B25"
$PN"B25"28;
"PETP2"
$PN"B24"129;
"PETN2"
$PN"B23"128;
"GND_B22"
$PN"B22"28;
"PETP1"
$PN"B21"127;
"PETN1"
$PN"B20"126;
"GND_B19"
$PN"B19"28;
"PETP0"
$PN"B18"131;
"PETN0"
$PN"B17"130;
"GND_B16"
$PN"B16"28;
"REFCLKP0"
$PN"B15"51;
"REFCLKN0"
$PN"B14"59;
"GND_B13"
$PN"B13"28;
"AUX_PWR_EN"
$PN"B12"52;
"+3.3V_EDGE"
$PN"B11"24;
"PERST0# \B"
$PN"B10"55;
"BIF2# \B"
$PN"B9"56;
"BIF1# \B"
$PN"B8"57;
"BIF0# \B"
$PN"B7"58;
"+12V_EDGE_B6"
$PN"B6"23;
"+12V_EDGE_B5"
$PN"B5"23;
"+12V_EDGE_B4"
$PN"B4"23;
"+12V_EDGE_B3"
$PN"B3"23;
"+12V_EDGE_B2"
$PN"B2"23;
"+12V_EDGE_B1"
$PN"B1"23;
"RBT_CRS_DV"
$PN"OB14"120;
"GND_OB13"
$PN"OB13"28;
"REFCLKP2"
$PN"OB12"40;
"REFCLKN2"
$PN"OB11"39;
"GND_OB10"
$PN"OB10"28;
"RBT_RXD0"
$PN"OB9"121;
"RBT_RXD1"
$PN"OB8"43;
"SLOT_ID0"
$PN"OB7"42;
"CLK"
$PN"OB6"38;
"DATA_OUT"
$PN"OB5"37;
"DATA_IN"
$PN"OB4"41;
"LD# \B"
$PN"OB3"36;
"MAIN_PWR_EN"
$PN"OB2"35;
"NIC_PWR_GOOD"
$PN"OB1"9;
%"Q_RES"
"2","(3125,5600)","0","pure_quanta","I169";
;
LOCATION"R1895"
$SEC"1"
CDS_SEC"1"
WATTAGE"1/16W"
MATERIAL"CHIP"
TOLERANCE"5%"
VALUE"0"
PACK_TYPE"0402LF"
CDS_LIB"pure_quanta"
PART_NUMBER"CS00002JB13";
"A"
$PN"1"13;
"B"
$PN"2"3;
%"Q_RES"
"2","(-3825,2250)","0","pure_quanta","I17";
;
LOCATION"R33"
$SEC"1"
CDS_SEC"1"
PACK_TYPE"0402LF"
MATERIAL"EMPTY"
WATTAGE"1/16W"
VALUE"4.7K"
TOLERANCE"1%"
CDS_LIB"pure_quanta"
PART_NUMBER"CS24702FB06";
"A"
$PN"1"27;
"B"
$PN"2"62;
%"Q_RES"
"1","(1775,5950)","0","pure_quanta","I170";
;
LOCATION"R48"
SEC"1"
WATTAGE"1/16W"
MATERIAL"CHIP"
PACK_TYPE"0402LF"
VALUE"200"
TOLERANCE"1%"
CDS_LIB"pure_quanta"
SEC_TYPE"0402LF"
PART_NUMBER"CS12002FB06";
"B"
$PN"2"10;
"A"
$PN"1"21;
%"Q_RES"
"1","(1775,6000)","0","pure_quanta","I171";
;
LOCATION"R47"
SEC"1"
MATERIAL"CHIP"
PACK_TYPE"0402LF"
WATTAGE"1/16W"
VALUE"200"
TOLERANCE"1%"
CDS_LIB"pure_quanta"
SEC_TYPE"0402LF"
PART_NUMBER"CS12002FB06";
"B"
$PN"2"11;
"A"
$PN"1"16;
%"Q_RES"
"1","(-750,1450)","0","pure_quanta","I19";
;
LOCATION"R8422"
$SEC"1"
CDS_SEC"1"
MATERIAL"CHIP"
TOLERANCE"1%"
VALUE"10K"
CDS_LIB"pure_quanta"
PACK_TYPE"0402LF"
WATTAGE"1/16W"
PART_NUMBER"CS31002FB08";
"B"
$PN"2"29;
"A"
$PN"1"68;
%"Q_RES"
"2","(-4300,1725)","0","pure_quanta","I2";
;
LOCATION"R32"
$SEC"1"
CDS_SEC"1"
PACK_TYPE"0402LF"
MATERIAL"CHIP"
TOLERANCE"1%"
WATTAGE"1/16W"
VALUE"4.7K"
CDS_LIB"pure_quanta"
PART_NUMBER"CS24702FB06";
"A"
$PN"1"61;
"B"
$PN"2"1;
%"Q_RES"
"1","(-750,1625)","0","pure_quanta","I20";
;
LOCATION"R8423"
$SEC"1"
CDS_SEC"1"
TOLERANCE"1%"
VALUE"1K"
PACK_TYPE"0402LF"
WATTAGE"1/16W"
MATERIAL"CHIP"
CDS_LIB"pure_quanta"
PART_NUMBER"CS21002FB06";
"B"
$PN"2"26;
"A"
$PN"1"67;
%"Q_RES"
"1","(-750,1800)","0","pure_quanta","I21";
;
LOCATION"R8421"
$SEC"1"
CDS_SEC"1"
TOLERANCE"1%"
VALUE"10K"
MATERIAL"CHIP"
PACK_TYPE"0402LF"
WATTAGE"1/16W"
CDS_LIB"pure_quanta"
PART_NUMBER"CS31002FB08";
"B"
$PN"2"26;
"A"
$PN"1"66;
%"Q_RES"
"1","(-750,1975)","0","pure_quanta","I22";
;
LOCATION"R8420"
$SEC"1"
CDS_SEC"1"
VALUE"1K"
WATTAGE"1/16W"
PACK_TYPE"0402LF"
TOLERANCE"1%"
MATERIAL"CHIP"
CDS_LIB"pure_quanta"
PART_NUMBER"CS21002FB06";
"B"
$PN"2"26;
"A"
$PN"1"69;
%"UNIVERSAL_GND"
"1","(-200,1325)","0","pure_quanta_power","I23";
;
ROOM"IO_SLOT"
CDS_LIB"pure_quanta_power"
HDL_POWER"GND";
"A"29;
%"TAP"
"1","(-1725,2850)","2","standard","I24";
;
CDS_LIB"standard"
BODY_TYPE"PLUMBING"
HDL_TAP"TRUE";
"B \NAC \NWC"6;
"S \NAC"
BN"15"73;
%"TAP"
"1","(-1725,3000)","2","standard","I25";
;
CDS_LIB"standard"
BODY_TYPE"PLUMBING"
HDL_TAP"TRUE";
"B \NAC \NWC"6;
"S \NAC"
BN"14"70;
%"TAP"
"1","(-1575,3050)","2","standard","I26";
;
CDS_LIB"standard"
BODY_TYPE"PLUMBING"
HDL_TAP"TRUE";
"B \NAC \NWC"7;
"S \NAC"
BN"14"71;
%"TAP"
"1","(-1575,2900)","2","standard","I27";
;
CDS_LIB"standard"
BODY_TYPE"PLUMBING"
HDL_TAP"TRUE";
"B \NAC \NWC"7;
"S \NAC"
BN"15"72;
%"UNIVERSAL_GND"
"1","(-1350,2500)","0","pure_quanta_power","I28";
;
ROOM"IO_SLOT"
CDS_LIB"pure_quanta_power"
HDL_POWER"GND";
"A"28;
%"TAP"
"1","(-1725,3300)","2","standard","I29";
;
CDS_LIB"standard"
BODY_TYPE"PLUMBING"
HDL_TAP"TRUE";
"B \NAC \NWC"6;
"S \NAC"
BN"12"112;
%"Q_RES"
"2","(-4300,2250)","0","pure_quanta","I3";
;
LOCATION"R31"
$SEC"1"
CDS_SEC"1"
WATTAGE"1/16W"
VALUE"4.7K"
PACK_TYPE"0402LF"
MATERIAL"EMPTY"
TOLERANCE"1%"
CDS_LIB"pure_quanta"
PART_NUMBER"CS24702FB06";
"A"
$PN"1"27;
"B"
$PN"2"61;
%"TAP"
"1","(-1725,3150)","2","standard","I30";
;
CDS_LIB"standard"
BODY_TYPE"PLUMBING"
HDL_TAP"TRUE";
"B \NAC \NWC"6;
"S \NAC"
BN"13"74;
%"TAP"
"1","(-1725,3450)","2","standard","I31";
;
CDS_LIB"standard"
BODY_TYPE"PLUMBING"
HDL_TAP"TRUE";
"B \NAC \NWC"6;
"S \NAC"
BN"11"75;
%"TAP"
"1","(-1575,3200)","2","standard","I32";
;
CDS_LIB"standard"
BODY_TYPE"PLUMBING"
HDL_TAP"TRUE";
"B \NAC \NWC"7;
"S \NAC"
BN"13"83;
%"TAP"
"1","(-1575,3500)","2","standard","I33";
;
CDS_LIB"standard"
BODY_TYPE"PLUMBING"
HDL_TAP"TRUE";
"B \NAC \NWC"7;
"S \NAC"
BN"11"77;
%"TAP"
"1","(-1725,3900)","2","standard","I34";
;
CDS_LIB"standard"
BODY_TYPE"PLUMBING"
HDL_TAP"TRUE";
"B \NAC \NWC"6;
"S \NAC"
BN"8"122;
%"TAP"
"1","(-1725,3600)","2","standard","I35";
;
CDS_LIB"standard"
BODY_TYPE"PLUMBING"
HDL_TAP"TRUE";
"B \NAC \NWC"6;
"S \NAC"
BN"10"76;
%"TAP"
"1","(-1725,3750)","2","standard","I36";
;
CDS_LIB"standard"
BODY_TYPE"PLUMBING"
HDL_TAP"TRUE";
"B \NAC \NWC"6;
"S \NAC"
BN"9"78;
%"TAP"
"1","(-1575,3650)","2","standard","I37";
;
CDS_LIB"standard"
BODY_TYPE"PLUMBING"
HDL_TAP"TRUE";
"B \NAC \NWC"7;
"S \NAC"
BN"10"81;
%"TAP"
"1","(-1575,3800)","2","standard","I38";
;
CDS_LIB"standard"
BODY_TYPE"PLUMBING"
HDL_TAP"TRUE";
"B \NAC \NWC"7;
"S \NAC"
BN"9"79;
%"TAP"
"1","(-1575,3950)","2","standard","I39";
;
CDS_LIB"standard"
BODY_TYPE"PLUMBING"
HDL_TAP"TRUE";
"B \NAC \NWC"7;
"S \NAC"
BN"8"80;
%"UNIVERSAL_POWER"
"1","(-4300,2550)","0","pure_quanta_power","I4";
;
HDL_POWER"P3V3_OCP_SFF"
CDS_LIB"pure_quanta_power";
"A"27;
%"UNIVERSAL_POWER"
"1","(-200,2125)","0","pure_quanta_power","I40";
;
HDL_POWER"P3V3_OCP_SFF"
CDS_LIB"pure_quanta_power";
"A"26;
%"UNIVERSAL_GND"
"1","(-4650,4325)","0","pure_quanta_power","I5";
;
CDS_LIB"pure_quanta_power"
HDL_POWER"GND";
"A"25;
%"Q_RES"
"1","(-2875,5750)","0","pure_quanta","I54";
;
LOCATION"R1671"
$SEC"1"
CDS_SEC"1"
PACK_TYPE"0402LF"
TOLERANCE"5%"
VALUE"0"
CDS_LIB"pure_quanta"
MATERIAL"CHIP"
WATTAGE"1/16W"
PART_NUMBER"CS00002JB13";
"B"
$PN"2"52;
"A"
$PN"1"44;
%"Q_RES"
"1","(-2875,5900)","0","pure_quanta","I55";
;
LOCATION"R41"
$SEC"1"
CDS_SEC"1"
TOLERANCE"5%"
VALUE"0"
PACK_TYPE"0402LF"
WATTAGE"1/16W"
MATERIAL"CHIP"
CDS_LIB"pure_quanta"
PART_NUMBER"CS00002JB13";
"B"
$PN"2"56;
"A"
$PN"1"84;
%"Q_RES"
"1","(-2875,5950)","0","pure_quanta","I56";
;
LOCATION"R40"
$SEC"1"
CDS_SEC"1"
TOLERANCE"5%"
VALUE"0"
PACK_TYPE"0402LF"
CDS_LIB"pure_quanta"
MATERIAL"CHIP"
WATTAGE"1/16W"
PART_NUMBER"CS00002JB13";
"B"
$PN"2"57;
"A"
$PN"1"86;
%"Q_RES"
"1","(-2875,6000)","0","pure_quanta","I57";
;
LOCATION"R39"
$SEC"1"
CDS_SEC"1"
VALUE"0"
TOLERANCE"5%"
MATERIAL"CHIP"
PACK_TYPE"0402LF"
WATTAGE"1/16W"
CDS_LIB"pure_quanta"
PART_NUMBER"CS00002JB13";
"B"
$PN"2"58;
"A"
$PN"1"85;
%"UNIVERSAL_POWER"
"1","(-2250,6175)","0","pure_quanta_power","I58";
;
HDL_POWER"P3V3_OCP_SFF"
CDS_LIB"pure_quanta_power";
"A"24;
%"Q_RES"
"1","(-2875,7050)","0","pure_quanta","I59";
;
LOCATION"R38"
$SEC"1"
CDS_SEC"1"
TOLERANCE"5%"
VALUE"0"
PACK_TYPE"0402LF"
CDS_LIB"pure_quanta"
WATTAGE"1/16W"
MATERIAL"CHIP"
PART_NUMBER"CS00002JB13";
"B"
$PN"2"35;
"A"
$PN"1"8;
%"Q_RES"
"1","(-4225,4425)","0","pure_quanta","I6";
;
LOCATION"R3132"
$SEC"1"
CDS_SEC"1"
WATTAGE"1/16W"
VALUE"100K"
MATERIAL"CHIP"
TOLERANCE"1%"
PACK_TYPE"0402LF"
CDS_LIB"pure_quanta"
PART_NUMBER"CS41002FB09";
"B"
$PN"2"54;
"A"
$PN"1"25;
%"Q_RES"
"1","(-4225,4625)","0","pure_quanta","I7";
;
LOCATION"R1930"
$SEC"1"
CDS_SEC"1"
MATERIAL"CHIP"
VALUE"10K"
TOLERANCE"1%"
PACK_TYPE"0402LF"
WATTAGE"1/16W"
CDS_LIB"pure_quanta"
PART_NUMBER"CS31002FB08";
"B"
$PN"2"53;
"A"
$PN"1"25;
%"TAP"
"1","(-1725,4400)","2","standard","I70";
;
CDS_LIB"standard"
BODY_TYPE"PLUMBING"
HDL_TAP"TRUE";
"B \NAC \NWC"6;
"S \NAC"
BN"6"124;
%"TAP"
"1","(-1725,4250)","2","standard","I71";
;
CDS_LIB"standard"
BODY_TYPE"PLUMBING"
HDL_TAP"TRUE";
"B \NAC \NWC"6;
"S \NAC"
BN"7"123;
%"TAP"
"1","(-1725,4550)","2","standard","I72";
;
CDS_LIB"standard"
BODY_TYPE"PLUMBING"
HDL_TAP"TRUE";
"B \NAC \NWC"6;
"S \NAC"
BN"5"91;
%"TAP"
"1","(-1575,4300)","2","standard","I73";
;
CDS_LIB"standard"
BODY_TYPE"PLUMBING"
HDL_TAP"TRUE";
"B \NAC \NWC"7;
"S \NAC"
BN"7"89;
%"TAP"
"1","(-1575,4450)","2","standard","I74";
;
CDS_LIB"standard"
BODY_TYPE"PLUMBING"
HDL_TAP"TRUE";
"B \NAC \NWC"7;
"S \NAC"
BN"6"90;
%"TAP"
"1","(-1575,4600)","2","standard","I75";
;
CDS_LIB"standard"
BODY_TYPE"PLUMBING"
HDL_TAP"TRUE";
"B \NAC \NWC"7;
"S \NAC"
BN"5"87;
%"TAP"
"1","(-1725,4700)","2","standard","I76";
;
CDS_LIB"standard"
BODY_TYPE"PLUMBING"
HDL_TAP"TRUE";
"B \NAC \NWC"6;
"S \NAC"
BN"4"125;
%"TAP"
"1","(-1725,5000)","2","standard","I77";
;
CDS_LIB"standard"
BODY_TYPE"PLUMBING"
HDL_TAP"TRUE";
"B \NAC \NWC"6;
"S \NAC"
BN"3"92;
%"TAP"
"1","(-1575,4750)","2","standard","I78";
;
CDS_LIB"standard"
BODY_TYPE"PLUMBING"
HDL_TAP"TRUE";
"B \NAC \NWC"7;
"S \NAC"
BN"4"88;
%"TAP"
"1","(-1575,5050)","2","standard","I79";
;
CDS_LIB"standard"
BODY_TYPE"PLUMBING"
HDL_TAP"TRUE";
"B \NAC \NWC"7;
"S \NAC"
BN"3"93;
%"Q_RES"
"1","(-4225,4725)","0","pure_quanta","I8";
;
LOCATION"R1929"
$SEC"1"
CDS_SEC"1"
WATTAGE"1/16W"
TOLERANCE"1%"
MATERIAL"CHIP"
VALUE"10K"
PACK_TYPE"0402LF"
CDS_LIB"pure_quanta"
PART_NUMBER"CS31002FB08";
"B"
$PN"2"45;
"A"
$PN"1"25;
%"TAP"
"1","(-1725,5150)","2","standard","I80";
;
CDS_LIB"standard"
BODY_TYPE"PLUMBING"
HDL_TAP"TRUE";
"B \NAC \NWC"6;
"S \NAC"
BN"2"129;
%"TAP"
"1","(-1725,5450)","2","standard","I81";
;
CDS_LIB"standard"
BODY_TYPE"PLUMBING"
HDL_TAP"TRUE";
"B \NAC \NWC"6;
"S \NAC"
BN"0"131;
%"TAP"
"1","(-1725,5300)","2","standard","I82";
;
CDS_LIB"standard"
BODY_TYPE"PLUMBING"
HDL_TAP"TRUE";
"B \NAC \NWC"6;
"S \NAC"
BN"1"127;
%"TAP"
"1","(-1575,5200)","2","standard","I83";
;
CDS_LIB"standard"
BODY_TYPE"PLUMBING"
HDL_TAP"TRUE";
"B \NAC \NWC"7;
"S \NAC"
BN"2"128;
%"TAP"
"1","(-1575,5350)","2","standard","I84";
;
CDS_LIB"standard"
BODY_TYPE"PLUMBING"
HDL_TAP"TRUE";
"B \NAC \NWC"7;
"S \NAC"
BN"1"126;
%"TAP"
"1","(-1575,5500)","2","standard","I85";
;
CDS_LIB"standard"
BODY_TYPE"PLUMBING"
HDL_TAP"TRUE";
"B \NAC \NWC"7;
"S \NAC"
BN"0"130;
%"UNIVERSAL_POWER"
"1","(-1425,7400)","0","pure_quanta_power","I86";
;
HDL_POWER"P12V_OCP_SFF_R"
CDS_LIB"pure_quanta_power";
"A"23;
%"Q_CAP"
"1","(825,1750)","0","pure_quanta","I87";
;
LOCATION"C1213"
$SEC"1"
CDS_SEC"1"
VALUE"22UF"
VOLTAGE"16V"
TOLERANCE"20%"
PACK_TYPE"C0805"
MATERIAL"X6S"
CDS_LIB"pure_quanta"
PART_NUMBER"CH6223MEA00";
"B"
$PN"2"32;
"A"
$PN"1"22;
%"Q_CAP"
"1","(1100,1750)","0","pure_quanta","I88";
;
LOCATION"C34"
$SEC"1"
CDS_SEC"1"
VOLTAGE"16V"
MATERIAL"X6S"
TOLERANCE"20%"
VALUE"22UF"
PACK_TYPE"C0805"
CDS_LIB"pure_quanta"
PART_NUMBER"CH6223MEA00";
"B"
$PN"2"32;
"A"
$PN"1"22;
%"Q_CAP"
"1","(1500,1750)","0","pure_quanta","I89";
;
LOCATION"C21"
$SEC"1"
CDS_SEC"1"
PACK_TYPE"0402"
MATERIAL"X7R"
VALUE"0.1UF"
VOLTAGE"25V"
TOLERANCE"10%"
CDS_LIB"pure_quanta"
PART_NUMBER"CH4104K1B00";
"B"
$PN"2"32;
"A"
$PN"1"22;
%"Q_CAP"
"1","(2050,1750)","0","pure_quanta","I90";
;
LOCATION"C1235"
$SEC"1"
CDS_SEC"1"
VALUE"0.1UF"
VOLTAGE"25V"
TOLERANCE"10%"
PACK_TYPE"0402"
MATERIAL"X7R"
CDS_LIB"pure_quanta"
PART_NUMBER"CH4104K1B00";
"B"
$PN"2"32;
"A"
$PN"1"22;
%"UNIVERSAL_GND"
"1","(575,2225)","0","pure_quanta_power","I91";
;
ROOM"IO_SLOT"
CDS_LIB"pure_quanta_power"
HDL_POWER"GND";
"A"17;
%"UNIVERSAL_POWER"
"1","(825,2100)","0","pure_quanta_power","I92";
;
HDL_POWER"P12V_OCP_SFF_R"
CDS_LIB"pure_quanta_power";
"A"22;
%"TAP"
"1","(775,3000)","0","standard","I93";
;
CDS_LIB"standard"
BODY_TYPE"PLUMBING"
HDL_TAP"TRUE";
"B \NAC \NWC"5;
"S \NAC"
BN"14"111;
%"TAP"
"1","(925,2900)","0","standard","I94";
;
CDS_LIB"standard"
BODY_TYPE"PLUMBING"
HDL_TAP"TRUE";
"B \NAC \NWC"4;
"S \NAC"
BN"15"137;
%"TAP"
"1","(925,3050)","0","standard","I95";
;
CDS_LIB"standard"
BODY_TYPE"PLUMBING"
HDL_TAP"TRUE";
"B \NAC \NWC"4;
"S \NAC"
BN"14"117;
%"TAP"
"1","(775,3150)","0","standard","I96";
;
CDS_LIB"standard"
BODY_TYPE"PLUMBING"
HDL_TAP"TRUE";
"B \NAC \NWC"5;
"S \NAC"
BN"13"116;
%"TAP"
"1","(775,3300)","0","standard","I97";
;
CDS_LIB"standard"
BODY_TYPE"PLUMBING"
HDL_TAP"TRUE";
"B \NAC \NWC"5;
"S \NAC"
BN"12"95;
%"TAP"
"1","(775,3450)","0","standard","I98";
;
CDS_LIB"standard"
BODY_TYPE"PLUMBING"
HDL_TAP"TRUE";
"B \NAC \NWC"5;
"S \NAC"
BN"11"97;
%"TAP"
"1","(925,3200)","0","standard","I99";
;
CDS_LIB"standard"
BODY_TYPE"PLUMBING"
HDL_TAP"TRUE";
"B \NAC \NWC"4;
"S \NAC"
BN"13"142;
END.
